(---------------------------------------------------------------------)
(                                                                     )
(    IPC-D-356                                                        )
(                                                                     )
(    Software Version : 17.2S081                                      )
(    Date/Time        : Tue Dec 13 16:32:28 2022                      )
(                                                                     )
(---------------------------------------------------------------------)


Warning: String OB252X315D126X189B252X315N_NPM exceeds record length on line 67 at column 0
Warning: String SMD36X115_PM30X111_CUT exceeds record length on line 84 at column 0
Warning: String SH32X124_SM32X124_CUT exceeds record length on line 119 at column 0
Warning: String SMD24X65_PM20X60_IY2-17 exceeds record length on line 129 at column 0
Warning: String SMD56X231_PM35X231_IX10-04 exceeds record length on line 153 at column 0
Warning: Found a mechanical pin at location (4645.67 -4980.31) with no drill - skipping.
Warning: Found a mechanical pin at location (-581.89 -4980.31) with no drill - skipping.
Warning: Found a mechanical pin at location (4645.67 4543.31) with no drill - skipping.
Warning: Found a mechanical pin at location (-581.89 4543.31) with no drill - skipping.
Warning: String 11_18 exceeds record length on line 7363 at column 27


------------------------------------------
SUMMARY:
  Errors:       0
  Warnings:    10
